# T6G (Grand Teton) — schematic netlist excerpt (pin names and nets, part order shuffled) for the footprints in the layout excerpt that follows; sources: Cadence DE-HDL packaged netlist, KiCad conversion of 04192023_DAF0TMB3IC0_F0TG_MB_C_brd_V02_OCP.brd

PC324_2  Q_CAP  1UF 25V 10% X6S  pkg C0402  page 215 : A = SW_P12V_AUX_PVDDCR_SOC_P1_FLT ; B = GND
C1109  Q_CAP  0.1UF 25V 10% X7R  pkg 0402  page 357 : A = P12V_OCP_V3_2 ; B = GND

(kicad_pcb
	(version 20260206)
	(generator "pcbnew")
	(generator_version "10.0")
	(general
		(thickness 1.6)
		(legacy_teardrops no)
	)
	(paper "A4")
	(title_block
		(title "04192023_DAF0TMB3IC0_F0TG_MB_C_brd_V02_OCP.brd")
		(comment 1 "Grand Teton / footprints 914-915 of 8354")
	)
	(layers
		(0 "F.Cu" signal "TOP")
		(4 "In1.Cu" signal "GND")
		(6 "In2.Cu" signal "IN1")
		(8 "In3.Cu" signal "GND1")
		(10 "In4.Cu" signal "IN2")
		(12 "In5.Cu" signal "GND2")
		(14 "In6.Cu" signal "IN3")
		(16 "In7.Cu" signal "GND3")
		(18 "In8.Cu" signal "VCC")
		(20 "In9.Cu" signal "VCC1")
		(22 "In10.Cu" signal "GND4")
		(24 "In11.Cu" signal "IN4")
		(26 "In12.Cu" signal "GND5")
		(28 "In13.Cu" signal "IN5")
		(30 "In14.Cu" signal "GND6")
		(32 "In15.Cu" signal "IN6")
		(34 "In16.Cu" signal "GND7")
		(2 "B.Cu" signal "BOTTOM")
		(9 "F.Adhes" user "F.Adhesive")
		(11 "B.Adhes" user "B.Adhesive")
		(13 "F.Paste" user "Package Geometry/Pastemask Top")
		(15 "B.Paste" user "Package Geometry/Pastemask Bottom")
		(5 "F.SilkS" user "Ref Des/Silkscreen Top")
		(7 "B.SilkS" user "Ref Des/Silkscreen Bottom")
		(1 "F.Mask" user "Board Geometry/Soldermask Top")
		(3 "B.Mask" user "Board Geometry/Soldermask Bottom")
		(17 "Dwgs.User" user "User.Drawings")
		(19 "Cmts.User" user "User.Comments")
		(21 "Eco1.User" user "User.Eco1")
		(23 "Eco2.User" user "User.Eco2")
		(25 "Edge.Cuts" user "Board Geometry/Outline")
		(27 "Margin" user)
		(31 "F.CrtYd" user "Package Geometry/Place Bound Top")
		(29 "B.CrtYd" user "Package Geometry/Place Bound Bottom")
		(35 "F.Fab" user "Ref Des/Assembly Top")
		(33 "B.Fab" user "Ref Des/Assembly Bottom")
	)
	(footprint ""
		(layer "F.Cu")
		(at 26.226516 -40.180514)
		(property "Reference" "C1109"
			(at 0 0 0)
			(layer "F.SilkS")
			(hide yes)
			(effects
				(font
					(size 1.27 1.27)
				)
			)
		)
		(property "Value" ""
			(at 0 0 0)
			(layer "F.Fab")
			(effects
				(font
					(size 1.27 1.27)
				)
			)
		)
		(duplicate_pad_numbers_are_jumpers no)
		(fp_line
			(start -0.7874 -0.4064)
			(end 0.7874 -0.4064)
			(stroke
				(width 0.1524)
				(type default)
			)
			(layer "F.SilkS")
		)
		(fp_line
			(start -0.7874 0.4064)
			(end -0.7874 -0.4064)
			(stroke
				(width 0.1524)
				(type default)
			)
			(layer "F.SilkS")
		)
		(fp_line
			(start 0.7874 -0.4064)
			(end 0.7874 0.4064)
			(stroke
				(width 0.1524)
				(type default)
			)
			(layer "F.SilkS")
		)
		(fp_line
			(start 0.7874 0.4064)
			(end -0.7874 0.4064)
			(stroke
				(width 0.1524)
				(type default)
			)
			(layer "F.SilkS")
		)
		(fp_line
			(start -0.67945 -0.305054)
			(end -0.12065 -0.305054)
			(stroke
				(width 0.1)
				(type default)
			)
			(layer "F.Fab")
		)
		(fp_line
			(start -0.67945 0.3048)
			(end -0.67945 -0.305054)
			(stroke
				(width 0.1)
				(type default)
			)
			(layer "F.Fab")
		)
		(fp_line
			(start -0.12065 -0.305054)
			(end -0.12065 -0.2794)
			(stroke
				(width 0.1)
				(type default)
			)
			(layer "F.Fab")
		)
		(fp_line
			(start -0.12065 -0.2794)
			(end 0.12065 -0.2794)
			(stroke
				(width 0.1)
				(type default)
			)
			(layer "F.Fab")
		)
		(fp_line
			(start -0.12065 0.2794)
			(end -0.12065 0.3048)
			(stroke
				(width 0.1)
				(type default)
			)
			(layer "F.Fab")
		)
		(fp_line
			(start -0.12065 0.3048)
			(end -0.67945 0.3048)
			(stroke
				(width 0.1)
				(type default)
			)
			(layer "F.Fab")
		)
		(fp_line
			(start 0.120396 0.2794)
			(end -0.12065 0.2794)
			(stroke
				(width 0.1)
				(type default)
			)
			(layer "F.Fab")
		)
		(fp_line
			(start 0.120396 0.3048)
			(end 0.120396 0.2794)
			(stroke
				(width 0.1)
				(type default)
			)
			(layer "F.Fab")
		)
		(fp_line
			(start 0.12065 -0.3048)
			(end 0.67945 -0.3048)
			(stroke
				(width 0.1)
				(type default)
			)
			(layer "F.Fab")
		)
		(fp_line
			(start 0.12065 -0.2794)
			(end 0.12065 -0.3048)
			(stroke
				(width 0.1)
				(type default)
			)
			(layer "F.Fab")
		)
		(fp_line
			(start 0.67945 -0.3048)
			(end 0.67945 0.3048)
			(stroke
				(width 0.1)
				(type default)
			)
			(layer "F.Fab")
		)
		(fp_line
			(start 0.67945 0.3048)
			(end 0.120396 0.3048)
			(stroke
				(width 0.1)
				(type default)
			)
			(layer "F.Fab")
		)
		(pad "1" smd circle
			(at -0.40005 0)
			(size 0 0)
			(layers "F.Cu" "F.Mask" "F.Paste")
			(net "P12V_OCP_V3_2")
		)
		(pad "2" smd circle
			(at 0.40005 0)
			(size 0 0)
			(layers "F.Cu" "F.Mask" "F.Paste")
			(net "GND")
		)
	)
	(footprint ""
		(layer "F.Cu")
		(at 120.327928 -165.109906 90)
		(property "Reference" "PC324_2"
			(at 0 0 90)
			(layer "F.SilkS")
			(hide yes)
			(effects
				(font
					(size 1.27 1.27)
				)
			)
		)
		(property "Value" ""
			(at 0 0 90)
			(layer "F.Fab")
			(effects
				(font
					(size 1.27 1.27)
				)
			)
		)
		(duplicate_pad_numbers_are_jumpers no)
		(fp_line
			(start 0.7874 -0.4064)
			(end 0.7874 0.4064)
			(stroke
				(width 0.1524)
				(type default)
			)
			(layer "F.SilkS")
		)
		(fp_line
			(start -0.7874 -0.4064)
			(end 0.7874 -0.4064)
			(stroke
				(width 0.1524)
				(type default)
			)
			(layer "F.SilkS")
		)
		(fp_line
			(start 0.7874 0.4064)
			(end -0.7874 0.4064)
			(stroke
				(width 0.1524)
				(type default)
			)
			(layer "F.SilkS")
		)
		(fp_line
			(start -0.7874 0.4064)
			(end -0.7874 -0.4064)
			(stroke
				(width 0.1524)
				(type default)
			)
			(layer "F.SilkS")
		)
		(fp_line
			(start -0.12065 -0.305054)
			(end -0.12065 -0.2794)
			(stroke
				(width 0.1)
				(type default)
			)
			(layer "F.Fab")
		)
		(fp_line
			(start -0.67945 -0.305054)
			(end -0.12065 -0.305054)
			(stroke
				(width 0.1)
				(type default)
			)
			(layer "F.Fab")
		)
		(fp_line
			(start 0.67945 -0.3048)
			(end 0.67945 0.3048)
			(stroke
				(width 0.1)
				(type default)
			)
			(layer "F.Fab")
		)
		(fp_line
			(start 0.12065 -0.3048)
			(end 0.67945 -0.3048)
			(stroke
				(width 0.1)
				(type default)
			)
			(layer "F.Fab")
		)
		(fp_line
			(start 0.12065 -0.2794)
			(end 0.12065 -0.3048)
			(stroke
				(width 0.1)
				(type default)
			)
			(layer "F.Fab")
		)
		(fp_line
			(start -0.12065 -0.2794)
			(end 0.12065 -0.2794)
			(stroke
				(width 0.1)
				(type default)
			)
			(layer "F.Fab")
		)
		(fp_line
			(start 0.120396 0.2794)
			(end -0.12065 0.2794)
			(stroke
				(width 0.1)
				(type default)
			)
			(layer "F.Fab")
		)
		(fp_line
			(start -0.12065 0.2794)
			(end -0.12065 0.3048)
			(stroke
				(width 0.1)
				(type default)
			)
			(layer "F.Fab")
		)
		(fp_line
			(start 0.67945 0.3048)
			(end 0.120396 0.3048)
			(stroke
				(width 0.1)
				(type default)
			)
			(layer "F.Fab")
		)
		(fp_line
			(start 0.120396 0.3048)
			(end 0.120396 0.2794)
			(stroke
				(width 0.1)
				(type default)
			)
			(layer "F.Fab")
		)
		(fp_line
			(start -0.12065 0.3048)
			(end -0.67945 0.3048)
			(stroke
				(width 0.1)
				(type default)
			)
			(layer "F.Fab")
		)
		(fp_line
			(start -0.67945 0.3048)
			(end -0.67945 -0.305054)
			(stroke
				(width 0.1)
				(type default)
			)
			(layer "F.Fab")
		)
		(pad "1" smd circle
			(at -0.40005 0 90)
			(size 0 0)
			(layers "F.Cu" "F.Mask" "F.Paste")
			(net "SW_P12V_AUX_PVDDCR_SOC_P1_FLT")
		)
		(pad "2" smd circle
			(at 0.40005 0 90)
			(size 0 0)
			(layers "F.Cu" "F.Mask" "F.Paste")
			(net "GND")
		)
	)
)
